FILE_TYPE = MACRO_DRAWING;
SET COLOR_WIRE YELLOW;
SET COLOR_PROP MONO;
SET COLOR_DOT WHITE;
SET COLOR_ARC YELLOW;
SET COLOR_BODY GREEN;
SET COLOR_NOTE MONO;
SET PROP_DISPLAY VALUE;
SET PAGE_NUMBER P9;
FORCEADD INTEL_CORP_BPAGE..1
(4250 200);
FORCEPROP 1 LAST CDS_CON_LAST_MODIFIED Fri Jun 16 17:48:00 2017
J 0
(2825 525);
PAINT ORANGE (2825 525);
DISPLAY INVISIBLE (2825 525);
FORCEPROP 1 LAST CUSTOM_TXT_CDS <CURRENT_DESIGN_SHEET> OF <TOTAL_DESIGN_SHEETS>
J 0
(3750 225);
PAINT ORANGE (3750 225);
FORCEPROP 1 LAST CUSTOM_TXT_CDS <CON_LAST_MODIFIED>
J 0
(250 300);
PAINT ORANGE (250 300);
FORCEPROP 2 LAST CUSTOM_TXT_CDS <XR_PAGE_TITLE>
J 0
(-3640 5450);
DISPLAY 0.638298 (-3640 5450);
PAINT PINK (-3640 5450);
DISPLAY INVISIBLE (-3640 5450);
FORCEPROP 1 LAST SCH_TITLE POWER BLOCK DIAGRAM
J 0
(-3700 250);
DISPLAY 1.212766 (-3700 250);
PAINT ORANGE (-3700 250);
FORCEPROP 2 LAST CDS_LIB mstr_symbols
J 0
(4250 200);
PAINT MONO (4250 200);
DISPLAY INVISIBLE (4250 200);
FORCEPROP 2 LAST PAGE_BORDER TRUE
J 0
(-3640 5450);
DISPLAY 0.638298 (-3640 5450);
PAINT PINK (-3640 5450);
DISPLAY INVISIBLE (-3640 5450);
FORCEPROP 1 LAST COMMENT_BODY TRUE
J 0
(4262 212);
DISPLAY 0.468085 (4262 212);
PAINT GREEN (4262 212);
DISPLAY INVISIBLE (4262 212);
FORCEPROP 2 LAST CDS_XR_PAGE_TITLE CR-9 : @BASEBOARD_FAB2_LIB.BASEBOARD_FAB2(SCH_1):PAGE9
J 0
(-3640 5450);
DISPLAY 0.638298 (-3640 5450);
PAINT PINK (-3640 5450);
DISPLAY INVISIBLE (-3640 5450);
FORCENOTE
$CDS_IMAGE|Power Block Diagram_0406_J.jpg|6234|4750
(325 2900) 0;
DISPLAY LEFT (325 2900);
QUIT
